(kicad_pcb
	(version 20260206)
	(generator "pcbnew")
	(generator_version "10.0")
	(general
		(thickness 1.6)
		(legacy_teardrops no)
	)
	(paper "A4")
	(title_block
		(title "01162023_DA0F0TEBIF0_F0T_Expander_BD_F_brd_V02_OCP.brd")
		(comment 1 "Grand Teton / footprints 8254-8261 of 9728")
	)
	(layers
		(0 "F.Cu" signal "TOP")
		(4 "In1.Cu" signal "GND")
		(6 "In2.Cu" signal "VCC")
		(8 "In3.Cu" signal "VCC1")
		(10 "In4.Cu" signal "GND1")
		(12 "In5.Cu" signal "IN1")
		(14 "In6.Cu" signal "GND2")
		(16 "In7.Cu" signal "IN2")
		(18 "In8.Cu" signal "GND3")
		(20 "In9.Cu" signal "IN3")
		(22 "In10.Cu" signal "GND4")
		(24 "In11.Cu" signal "IN4")
		(26 "In12.Cu" signal "GND5")
		(28 "In13.Cu" signal "IN5")
		(30 "In14.Cu" signal "GND6")
		(32 "In15.Cu" signal "IN6")
		(34 "In16.Cu" signal "GND7")
		(2 "B.Cu" signal "BOTTOM")
		(9 "F.Adhes" user "F.Adhesive")
		(11 "B.Adhes" user "B.Adhesive")
		(13 "F.Paste" user "Package Geometry/Pastemask Top")
		(15 "B.Paste" user "Package Geometry/Pastemask Bottom")
		(5 "F.SilkS" user "Ref Des/Silkscreen Top")
		(7 "B.SilkS" user "Ref Des/Silkscreen Bottom")
		(1 "F.Mask" user "Board Geometry/Soldermask Top")
		(3 "B.Mask" user "Board Geometry/Soldermask Bottom")
		(17 "Dwgs.User" user "User.Drawings")
		(19 "Cmts.User" user "User.Comments")
		(21 "Eco1.User" user "User.Eco1")
		(23 "Eco2.User" user "User.Eco2")
		(25 "Edge.Cuts" user "Board Geometry/Outline")
		(27 "Margin" user)
		(31 "F.CrtYd" user "Package Geometry/Place Bound Top")
		(29 "B.CrtYd" user "Package Geometry/Place Bound Bottom")
		(35 "F.Fab" user "Ref Des/Assembly Top")
		(33 "B.Fab" user "Ref Des/Assembly Bottom")
	)
	(footprint ""
		(layer "B.Cu")
		(at 236.262418 -278.898604 -90)
		(property "Reference" "C4346"
			(at 0 0 90)
			(layer "B.SilkS")
			(hide yes)
			(effects
				(font
					(size 1.27 1.27)
				)
				(justify mirror)
			)
		)
		(property "Value" ""
			(at 0 0 90)
			(layer "B.Fab")
			(effects
				(font
					(size 1.27 1.27)
				)
				(justify mirror)
			)
		)
		(duplicate_pad_numbers_are_jumpers no)
		(fp_line
			(start -1.2954 0.5842)
			(end 1.2954 0.5842)
			(stroke
				(width 0.1524)
				(type default)
			)
			(layer "B.SilkS")
		)
		(fp_line
			(start 1.2954 0.5842)
			(end 1.2954 -0.5842)
			(stroke
				(width 0.1524)
				(type default)
			)
			(layer "B.SilkS")
		)
		(fp_line
			(start -1.2954 -0.5842)
			(end -1.2954 0.5842)
			(stroke
				(width 0.1524)
				(type default)
			)
			(layer "B.SilkS")
		)
		(fp_line
			(start 1.2954 -0.5842)
			(end -1.2954 -0.5842)
			(stroke
				(width 0.1524)
				(type default)
			)
			(layer "B.SilkS")
		)
		(fp_line
			(start -0.8636 0.4572)
			(end 0.8636 0.4572)
			(stroke
				(width 0.1)
				(type default)
			)
			(layer "B.Fab")
		)
		(fp_line
			(start 0.8636 0.4572)
			(end 0.8636 0.4064)
			(stroke
				(width 0.1)
				(type default)
			)
			(layer "B.Fab")
		)
		(fp_line
			(start -1.1938 0.4064)
			(end -0.8636 0.4064)
			(stroke
				(width 0.1)
				(type default)
			)
			(layer "B.Fab")
		)
		(fp_line
			(start -0.8636 0.4064)
			(end -0.8636 0.4572)
			(stroke
				(width 0.1)
				(type default)
			)
			(layer "B.Fab")
		)
		(fp_line
			(start 0.8636 0.4064)
			(end 1.1938 0.4064)
			(stroke
				(width 0.1)
				(type default)
			)
			(layer "B.Fab")
		)
		(fp_line
			(start 1.1938 0.4064)
			(end 1.1938 -0.4064)
			(stroke
				(width 0.1)
				(type default)
			)
			(layer "B.Fab")
		)
		(fp_line
			(start -1.1938 -0.4064)
			(end -1.1938 0.4064)
			(stroke
				(width 0.1)
				(type default)
			)
			(layer "B.Fab")
		)
		(fp_line
			(start -0.8636 -0.4064)
			(end -1.1938 -0.4064)
			(stroke
				(width 0.1)
				(type default)
			)
			(layer "B.Fab")
		)
		(fp_line
			(start 0.8636 -0.4064)
			(end 0.8636 -0.4572)
			(stroke
				(width 0.1)
				(type default)
			)
			(layer "B.Fab")
		)
		(fp_line
			(start 1.1938 -0.4064)
			(end 0.8636 -0.4064)
			(stroke
				(width 0.1)
				(type default)
			)
			(layer "B.Fab")
		)
		(fp_line
			(start -0.8636 -0.4572)
			(end -0.8636 -0.4064)
			(stroke
				(width 0.1)
				(type default)
			)
			(layer "B.Fab")
		)
		(fp_line
			(start 0.8636 -0.4572)
			(end -0.8636 -0.4572)
			(stroke
				(width 0.1)
				(type default)
			)
			(layer "B.Fab")
		)
		(pad "1" smd rect
			(at 0.7366 0 180)
			(size 0.7112 0.8128)
			(layers "B.Cu" "B.Mask" "B.Paste")
			(net "P1V25_PEX2")
		)
		(pad "2" smd rect
			(at -0.7366 0 180)
			(size 0.7112 0.8128)
			(layers "B.Cu" "B.Mask" "B.Paste")
			(net "GND")
		)
	)
	(footprint ""
		(layer "B.Cu")
		(at 11.196066 -389.350504 90)
		(property "Reference" "C4474"
			(at 0 0 90)
			(layer "B.SilkS")
			(hide yes)
			(effects
				(font
					(size 1.27 1.27)
				)
				(justify mirror)
			)
		)
		(property "Value" ""
			(at 0 0 90)
			(layer "B.Fab")
			(effects
				(font
					(size 1.27 1.27)
				)
				(justify mirror)
			)
		)
		(duplicate_pad_numbers_are_jumpers no)
		(fp_line
			(start 1.524 -0.762)
			(end -1.524 -0.762)
			(stroke
				(width 0.1524)
				(type default)
			)
			(layer "B.SilkS")
		)
		(fp_line
			(start -1.524 -0.762)
			(end -1.524 0.762)
			(stroke
				(width 0.1524)
				(type default)
			)
			(layer "B.SilkS")
		)
		(fp_line
			(start 1.524 0.762)
			(end 1.524 -0.762)
			(stroke
				(width 0.1524)
				(type default)
			)
			(layer "B.SilkS")
		)
		(fp_line
			(start -1.524 0.762)
			(end 1.524 0.762)
			(stroke
				(width 0.1524)
				(type default)
			)
			(layer "B.SilkS")
		)
		(fp_line
			(start 1.1049 -0.724916)
			(end 1.1049 0.724916)
			(stroke
				(width 0.1)
				(type default)
			)
			(layer "B.Fab")
		)
		(fp_line
			(start -1.1049 -0.724916)
			(end 1.1049 -0.724916)
			(stroke
				(width 0.1)
				(type default)
			)
			(layer "B.Fab")
		)
		(fp_line
			(start 1.1049 0.724916)
			(end -1.1049 0.724916)
			(stroke
				(width 0.1)
				(type default)
			)
			(layer "B.Fab")
		)
		(fp_line
			(start -1.1049 0.724916)
			(end -1.1049 -0.724916)
			(stroke
				(width 0.1)
				(type default)
			)
			(layer "B.Fab")
		)
		(pad "1" smd rect
			(at 0.889 0 90)
			(size 1.016 1.27)
			(layers "B.Cu" "B.Mask" "B.Paste")
			(net "P1V2_USB_8042")
		)
		(pad "2" smd rect
			(at -0.889 0 90)
			(size 1.016 1.27)
			(layers "B.Cu" "B.Mask" "B.Paste")
			(net "GND")
		)
	)
	(footprint ""
		(layer "B.Cu")
		(at 103.748586 -344.563954 90)
		(property "Reference" "R6366"
			(at 0 0 90)
			(layer "B.SilkS")
			(hide yes)
			(effects
				(font
					(size 1.27 1.27)
				)
				(justify mirror)
			)
		)
		(property "Value" ""
			(at 0 0 90)
			(layer "B.Fab")
			(effects
				(font
					(size 1.27 1.27)
				)
				(justify mirror)
			)
		)
		(duplicate_pad_numbers_are_jumpers no)
		(fp_line
			(start 0.7874 -0.4064)
			(end -0.7874 -0.4064)
			(stroke
				(width 0.1524)
				(type default)
			)
			(layer "B.SilkS")
		)
		(fp_line
			(start -0.7874 -0.4064)
			(end -0.7874 0.4064)
			(stroke
				(width 0.1524)
				(type default)
			)
			(layer "B.SilkS")
		)
		(fp_line
			(start 0.7874 0.4064)
			(end 0.7874 -0.4064)
			(stroke
				(width 0.1524)
				(type default)
			)
			(layer "B.SilkS")
		)
		(fp_line
			(start -0.7874 0.4064)
			(end 0.7874 0.4064)
			(stroke
				(width 0.1524)
				(type default)
			)
			(layer "B.SilkS")
		)
		(fp_line
			(start 0.67945 -0.305054)
			(end 0.12065 -0.305054)
			(stroke
				(width 0.1)
				(type default)
			)
			(layer "B.Fab")
		)
		(fp_line
			(start 0.12065 -0.305054)
			(end 0.12065 -0.2794)
			(stroke
				(width 0.1)
				(type default)
			)
			(layer "B.Fab")
		)
		(fp_line
			(start -0.12065 -0.3048)
			(end -0.67945 -0.3048)
			(stroke
				(width 0.1)
				(type default)
			)
			(layer "B.Fab")
		)
		(fp_line
			(start -0.67945 -0.3048)
			(end -0.67945 0.3048)
			(stroke
				(width 0.1)
				(type default)
			)
			(layer "B.Fab")
		)
		(fp_line
			(start 0.12065 -0.2794)
			(end -0.12065 -0.2794)
			(stroke
				(width 0.1)
				(type default)
			)
			(layer "B.Fab")
		)
		(fp_line
			(start -0.12065 -0.2794)
			(end -0.12065 -0.3048)
			(stroke
				(width 0.1)
				(type default)
			)
			(layer "B.Fab")
		)
		(fp_line
			(start 0.12065 0.2794)
			(end 0.12065 0.3048)
			(stroke
				(width 0.1)
				(type default)
			)
			(layer "B.Fab")
		)
		(fp_line
			(start -0.120396 0.2794)
			(end 0.12065 0.2794)
			(stroke
				(width 0.1)
				(type default)
			)
			(layer "B.Fab")
		)
		(fp_line
			(start 0.67945 0.3048)
			(end 0.67945 -0.305054)
			(stroke
				(width 0.1)
				(type default)
			)
			(layer "B.Fab")
		)
		(fp_line
			(start 0.12065 0.3048)
			(end 0.67945 0.3048)
			(stroke
				(width 0.1)
				(type default)
			)
			(layer "B.Fab")
		)
		(fp_line
			(start -0.120396 0.3048)
			(end -0.120396 0.2794)
			(stroke
				(width 0.1)
				(type default)
			)
			(layer "B.Fab")
		)
		(fp_line
			(start -0.67945 0.3048)
			(end -0.120396 0.3048)
			(stroke
				(width 0.1)
				(type default)
			)
			(layer "B.Fab")
		)
		(pad "1" smd circle
			(at 0.40005 0 270)
			(size 0 0)
			(layers "B.Cu" "B.Mask" "B.Paste")
			(net "CLK_100M_MB_1_R_DP")
		)
		(pad "2" smd circle
			(at -0.40005 0 270)
			(size 0 0)
			(layers "B.Cu" "B.Mask" "B.Paste")
			(net "CLK_100M_MB_1_DP")
		)
	)
	(footprint ""
		(layer "B.Cu")
		(at 294.69969 -301.599854 -90)
		(property "Reference" "C1749"
			(at 0 0 90)
			(layer "B.SilkS")
			(hide yes)
			(effects
				(font
					(size 1.27 1.27)
				)
				(justify mirror)
			)
		)
		(property "Value" ""
			(at 0 0 90)
			(layer "B.Fab")
			(effects
				(font
					(size 1.27 1.27)
				)
				(justify mirror)
			)
		)
		(duplicate_pad_numbers_are_jumpers no)
		(fp_line
			(start -0.299974 0.150114)
			(end 0.299974 0.150114)
			(stroke
				(width 0.1)
				(type default)
			)
			(layer "B.Fab")
		)
		(fp_line
			(start 0.299974 0.150114)
			(end 0.299974 -0.150114)
			(stroke
				(width 0.1)
				(type default)
			)
			(layer "B.Fab")
		)
		(fp_line
			(start -0.299974 -0.150114)
			(end -0.299974 0.150114)
			(stroke
				(width 0.1)
				(type default)
			)
			(layer "B.Fab")
		)
		(fp_line
			(start 0.299974 -0.150114)
			(end -0.299974 -0.150114)
			(stroke
				(width 0.1)
				(type default)
			)
			(layer "B.Fab")
		)
		(pad "1" smd rect
			(at 0.2667 0 90)
			(size 0.3048 0.381)
			(layers "B.Cu" "B.Mask" "B.Paste")
			(net "P0V8_SERDES_VDDA_PEX2")
		)
		(pad "2" smd rect
			(at -0.2667 0 90)
			(size 0.3048 0.381)
			(layers "B.Cu" "B.Mask" "B.Paste")
			(net "GND")
		)
	)
	(footprint ""
		(layer "B.Cu")
		(at 337.16087 -284.796738 -90)
		(property "Reference" "PC159"
			(at 0 0 90)
			(layer "B.SilkS")
			(hide yes)
			(effects
				(font
					(size 1.27 1.27)
				)
				(justify mirror)
			)
		)
		(property "Value" ""
			(at 0 0 90)
			(layer "B.Fab")
			(effects
				(font
					(size 1.27 1.27)
				)
				(justify mirror)
			)
		)
		(duplicate_pad_numbers_are_jumpers no)
		(fp_line
			(start -1.524 0.762)
			(end 1.524 0.762)
			(stroke
				(width 0.1524)
				(type default)
			)
			(layer "B.SilkS")
		)
		(fp_line
			(start 1.524 0.762)
			(end 1.524 -0.762)
			(stroke
				(width 0.1524)
				(type default)
			)
			(layer "B.SilkS")
		)
		(fp_line
			(start -1.524 -0.762)
			(end -1.524 0.762)
			(stroke
				(width 0.1524)
				(type default)
			)
			(layer "B.SilkS")
		)
		(fp_line
			(start 1.524 -0.762)
			(end -1.524 -0.762)
			(stroke
				(width 0.1524)
				(type default)
			)
			(layer "B.SilkS")
		)
		(fp_line
			(start -1.1049 0.724916)
			(end -1.1049 -0.724916)
			(stroke
				(width 0.1)
				(type default)
			)
			(layer "B.Fab")
		)
		(fp_line
			(start 1.1049 0.724916)
			(end -1.1049 0.724916)
			(stroke
				(width 0.1)
				(type default)
			)
			(layer "B.Fab")
		)
		(fp_line
			(start -1.1049 -0.724916)
			(end 1.1049 -0.724916)
			(stroke
				(width 0.1)
				(type default)
			)
			(layer "B.Fab")
		)
		(fp_line
			(start 1.1049 -0.724916)
			(end 1.1049 0.724916)
			(stroke
				(width 0.1)
				(type default)
			)
			(layer "B.Fab")
		)
		(pad "1" smd rect
			(at 0.889 0 270)
			(size 1.016 1.27)
			(layers "B.Cu" "B.Mask" "B.Paste")
			(net "SW_P12V_P0V8_PEX2_FLT")
		)
		(pad "2" smd rect
			(at -0.889 0 270)
			(size 1.016 1.27)
			(layers "B.Cu" "B.Mask" "B.Paste")
			(net "GND")
		)
	)
	(footprint ""
		(layer "B.Cu")
		(at 307.916834 -295.42486)
		(property "Reference" "C3249"
			(at 0 0 0)
			(layer "B.SilkS")
			(hide yes)
			(effects
				(font
					(size 1.27 1.27)
				)
				(justify mirror)
			)
		)
		(property "Value" ""
			(at 0 0 0)
			(layer "B.Fab")
			(effects
				(font
					(size 1.27 1.27)
				)
				(justify mirror)
			)
		)
		(duplicate_pad_numbers_are_jumpers no)
		(fp_line
			(start -1.2954 -0.5842)
			(end -1.2954 0.5842)
			(stroke
				(width 0.1524)
				(type default)
			)
			(layer "B.SilkS")
		)
		(fp_line
			(start -1.2954 0.5842)
			(end 1.2954 0.5842)
			(stroke
				(width 0.1524)
				(type default)
			)
			(layer "B.SilkS")
		)
		(fp_line
			(start 1.2954 -0.5842)
			(end -1.2954 -0.5842)
			(stroke
				(width 0.1524)
				(type default)
			)
			(layer "B.SilkS")
		)
		(fp_line
			(start 1.2954 0.5842)
			(end 1.2954 -0.5842)
			(stroke
				(width 0.1524)
				(type default)
			)
			(layer "B.SilkS")
		)
		(fp_line
			(start -1.1938 -0.4064)
			(end -1.1938 0.4064)
			(stroke
				(width 0.1)
				(type default)
			)
			(layer "B.Fab")
		)
		(fp_line
			(start -1.1938 0.4064)
			(end -0.8636 0.4064)
			(stroke
				(width 0.1)
				(type default)
			)
			(layer "B.Fab")
		)
		(fp_line
			(start -0.8636 -0.4572)
			(end -0.8636 -0.4064)
			(stroke
				(width 0.1)
				(type default)
			)
			(layer "B.Fab")
		)
		(fp_line
			(start -0.8636 -0.4064)
			(end -1.1938 -0.4064)
			(stroke
				(width 0.1)
				(type default)
			)
			(layer "B.Fab")
		)
		(fp_line
			(start -0.8636 0.4064)
			(end -0.8636 0.4572)
			(stroke
				(width 0.1)
				(type default)
			)
			(layer "B.Fab")
		)
		(fp_line
			(start -0.8636 0.4572)
			(end 0.8636 0.4572)
			(stroke
				(width 0.1)
				(type default)
			)
			(layer "B.Fab")
		)
		(fp_line
			(start 0.8636 -0.4572)
			(end -0.8636 -0.4572)
			(stroke
				(width 0.1)
				(type default)
			)
			(layer "B.Fab")
		)
		(fp_line
			(start 0.8636 -0.4064)
			(end 0.8636 -0.4572)
			(stroke
				(width 0.1)
				(type default)
			)
			(layer "B.Fab")
		)
		(fp_line
			(start 0.8636 0.4064)
			(end 1.1938 0.4064)
			(stroke
				(width 0.1)
				(type default)
			)
			(layer "B.Fab")
		)
		(fp_line
			(start 0.8636 0.4572)
			(end 0.8636 0.4064)
			(stroke
				(width 0.1)
				(type default)
			)
			(layer "B.Fab")
		)
		(fp_line
			(start 1.1938 -0.4064)
			(end 0.8636 -0.4064)
			(stroke
				(width 0.1)
				(type default)
			)
			(layer "B.Fab")
		)
		(fp_line
			(start 1.1938 0.4064)
			(end 1.1938 -0.4064)
			(stroke
				(width 0.1)
				(type default)
			)
			(layer "B.Fab")
		)
		(pad "1" smd rect
			(at 0.7366 0 270)
			(size 0.7112 0.8128)
			(layers "B.Cu" "B.Mask" "B.Paste")
			(net "P1V25_PEX2")
		)
		(pad "2" smd rect
			(at -0.7366 0 270)
			(size 0.7112 0.8128)
			(layers "B.Cu" "B.Mask" "B.Paste")
			(net "GND")
		)
	)
	(footprint ""
		(layer "B.Cu")
		(at 162.226244 -139.8016 180)
		(property "Reference" "C885"
			(at 0 0 0)
			(layer "B.SilkS")
			(hide yes)
			(effects
				(font
					(size 1.27 1.27)
				)
				(justify mirror)
			)
		)
		(property "Value" ""
			(at 0 0 0)
			(layer "B.Fab")
			(effects
				(font
					(size 1.27 1.27)
				)
				(justify mirror)
			)
		)
		(duplicate_pad_numbers_are_jumpers no)
		(fp_line
			(start 0.7874 0.4064)
			(end 0.7874 -0.4064)
			(stroke
				(width 0.1524)
				(type default)
			)
			(layer "B.SilkS")
		)
		(fp_line
			(start 0.7874 -0.4064)
			(end -0.7874 -0.4064)
			(stroke
				(width 0.1524)
				(type default)
			)
			(layer "B.SilkS")
		)
		(fp_line
			(start -0.7874 0.4064)
			(end 0.7874 0.4064)
			(stroke
				(width 0.1524)
				(type default)
			)
			(layer "B.SilkS")
		)
		(fp_line
			(start -0.7874 -0.4064)
			(end -0.7874 0.4064)
			(stroke
				(width 0.1524)
				(type default)
			)
			(layer "B.SilkS")
		)
		(fp_line
			(start 0.67945 0.3048)
			(end 0.67945 -0.305054)
			(stroke
				(width 0.1)
				(type default)
			)
			(layer "B.Fab")
		)
		(fp_line
			(start 0.67945 -0.305054)
			(end 0.12065 -0.305054)
			(stroke
				(width 0.1)
				(type default)
			)
			(layer "B.Fab")
		)
		(fp_line
			(start 0.12065 0.3048)
			(end 0.67945 0.3048)
			(stroke
				(width 0.1)
				(type default)
			)
			(layer "B.Fab")
		)
		(fp_line
			(start 0.12065 0.2794)
			(end 0.12065 0.3048)
			(stroke
				(width 0.1)
				(type default)
			)
			(layer "B.Fab")
		)
		(fp_line
			(start 0.12065 -0.2794)
			(end -0.12065 -0.2794)
			(stroke
				(width 0.1)
				(type default)
			)
			(layer "B.Fab")
		)
		(fp_line
			(start 0.12065 -0.305054)
			(end 0.12065 -0.2794)
			(stroke
				(width 0.1)
				(type default)
			)
			(layer "B.Fab")
		)
		(fp_line
			(start -0.120396 0.3048)
			(end -0.120396 0.2794)
			(stroke
				(width 0.1)
				(type default)
			)
			(layer "B.Fab")
		)
		(fp_line
			(start -0.120396 0.2794)
			(end 0.12065 0.2794)
			(stroke
				(width 0.1)
				(type default)
			)
			(layer "B.Fab")
		)
		(fp_line
			(start -0.12065 -0.2794)
			(end -0.12065 -0.3048)
			(stroke
				(width 0.1)
				(type default)
			)
			(layer "B.Fab")
		)
		(fp_line
			(start -0.12065 -0.3048)
			(end -0.67945 -0.3048)
			(stroke
				(width 0.1)
				(type default)
			)
			(layer "B.Fab")
		)
		(fp_line
			(start -0.67945 0.3048)
			(end -0.120396 0.3048)
			(stroke
				(width 0.1)
				(type default)
			)
			(layer "B.Fab")
		)
		(fp_line
			(start -0.67945 -0.3048)
			(end -0.67945 0.3048)
			(stroke
				(width 0.1)
				(type default)
			)
			(layer "B.Fab")
		)
		(pad "1" smd circle
			(at 0.40005 0)
			(size 0 0)
			(layers "B.Cu" "B.Mask" "B.Paste")
			(net "P3V3_NIC2")
		)
		(pad "2" smd circle
			(at -0.40005 0)
			(size 0 0)
			(layers "B.Cu" "B.Mask" "B.Paste")
			(net "GND")
		)
	)
	(footprint ""
		(layer "B.Cu")
		(at 64.399922 -292.099746 90)
		(property "Reference" "C1209"
			(at 0 0 90)
			(layer "B.SilkS")
			(hide yes)
			(effects
				(font
					(size 1.27 1.27)
				)
				(justify mirror)
			)
		)
		(property "Value" ""
			(at 0 0 90)
			(layer "B.Fab")
			(effects
				(font
					(size 1.27 1.27)
				)
				(justify mirror)
			)
		)
		(duplicate_pad_numbers_are_jumpers no)
		(fp_line
			(start 0.299974 -0.150114)
			(end -0.299974 -0.150114)
			(stroke
				(width 0.1)
				(type default)
			)
			(layer "B.Fab")
		)
		(fp_line
			(start -0.299974 -0.150114)
			(end -0.299974 0.150114)
			(stroke
				(width 0.1)
				(type default)
			)
			(layer "B.Fab")
		)
		(fp_line
			(start 0.299974 0.150114)
			(end 0.299974 -0.150114)
			(stroke
				(width 0.1)
				(type default)
			)
			(layer "B.Fab")
		)
		(fp_line
			(start -0.299974 0.150114)
			(end 0.299974 0.150114)
			(stroke
				(width 0.1)
				(type default)
			)
			(layer "B.Fab")
		)
		(pad "1" smd rect
			(at 0.2667 0 270)
			(size 0.3048 0.381)
			(layers "B.Cu" "B.Mask" "B.Paste")
			(net "P0V8_SERDES_VDDA_PEX0")
		)
		(pad "2" smd rect
			(at -0.2667 0 270)
			(size 0.3048 0.381)
			(layers "B.Cu" "B.Mask" "B.Paste")
			(net "GND")
		)
	)
)
